# S9S_MB_2U (Grand Teton) — schematic parts with pin connectivity, parts 2063–2206 of 6093; source: Cadence DE-HDL packaged netlist (pstxprt.dat, pstxnet.dat, pstchip.dat)

PC591  Q_CAP  2.2UF 16V 10% X6S  pkg C0603  page 259 : 1 = P3V3_AUX_VCC ; 2 = GND
PC594  Q_CAP  3300PF 50V 10% X7R  pkg 0402  page 266 : 1 = SH_PVCCFA_EHV_FIVRA_CPU0_R ; 2 = VSENSE_PVCCFA_EHV_FIVRA_CPU0_DN
PC600  Q_CAP  2.2UF 10V 10% X6S  pkg C0402  page 271 : 1 = PVCCFA_EHV_FIVRA_CPU0_VDD1 ; 2 = GND
PC601  Q_CAP  2.2UF 10V 10% X6S  pkg C0402  page 271 : 1 = PVCCFA_EHV_FIVRA_CPU0_VDD2 ; 2 = GND
PC602_P0_1  Q_CAP  3300PF 50V 10% X7R  pkg 0402  page 271 : 1 = SW_P12V_PVCCFA_EHV_FIVRA_CPU0_R ; 2 = GND
PC603_P0_2  Q_CAP  3300PF 50V 10% X7R  pkg 0402  page 271 : 1 = SW_P12V_PVCCFA_EHV_FIVRA_CPU0_L ; 2 = GND
PC604_P0_1  Q_CAP  1UF 16V 10% X6S  pkg C0402  page 271 : 1 = SW_P12V_PVCCFA_EHV_FIVRA_CPU0_R ; 2 = GND
PC605_P0_2  Q_CAP  1UF 16V 10% X6S  pkg C0402  page 271 : 1 = SW_P12V_PVCCFA_EHV_FIVRA_CPU0_L ; 2 = GND
PC606  Q_CAP  100NF 50V 10% X7R  pkg C0402  page 271 : 1 = SW_PVCCFA_EHV_FIVRA_CPU0_BOOT1_ ; 2 = SW_PVCCFA_EHV_FIVRA_CPU0_BOOTR1
PC607  Q_CAP  100NF 50V 10% X7R  pkg C0402  page 271 : 1 = SW_PVCCFA_EHV_FIVRA_CPU0_BOOT2_ ; 2 = SW_PVCCFA_EHV_FIVRA_CPU0_BOOTR2
PC608_P0_1  Q_CAP  22UF 16V 20% X6S  pkg C0805  page 271 : 1 = SW_P12V_PVCCFA_EHV_FIVRA_CPU0_R ; 2 = GND
PC609_P0_2  Q_CAP  22UF 16V 20% X6S  pkg C0805  page 271 : 1 = SW_P12V_PVCCFA_EHV_FIVRA_CPU0_L ; 2 = GND
PC610_P0_1  Q_CAP  22UF 16V 20% X6S  pkg C0805  page 271 : 1 = SW_P12V_PVCCFA_EHV_FIVRA_CPU0_R ; 2 = GND
PC611_P0_2  Q_CAP  22UF 16V 20% X6S  pkg C0805  page 271 : 1 = SW_P12V_PVCCFA_EHV_FIVRA_CPU0_L ; 2 = GND
PC612_P0_1  Q_CAP  100NF 50V 10% X7R  pkg C0402  page 271 : 1 = PVCCFA_EHV_FIVRA_CPU0 ; 2 = GND
PC613_P0_2  Q_CAP  1UF 16V 10% X6S  pkg C0402  page 271 : 1 = PVCCFA_EHV_FIVRA_CPU0 ; 2 = GND
PC615_P0_1  Q_CAP  22UF 4V 20% X6S  pkg C0805  page 271 : 1 = PVCCFA_EHV_FIVRA_CPU0 ; 2 = GND
PC616_P0_2  Q_CAP  22UF 4V 20% X6S  pkg C0805  page 271 : 1 = PVCCFA_EHV_FIVRA_CPU0 ; 2 = GND
PC617_P0_1  Q_CAP  22UF 4V 20% X6S  pkg C0805  page 271 : 1 = PVCCFA_EHV_FIVRA_CPU0 ; 2 = GND
PC618_P0_2  Q_CAP  22UF 4V 20% X6S  pkg C0805  page 271 : 1 = PVCCFA_EHV_FIVRA_CPU0 ; 2 = GND
PC619  Q_CAPP  560UF 2.5V 20% OSCON  pkg THLF  page 271 : 1 = PVCCFA_EHV_FIVRA_CPU0 ; 2 = GND
PC620  Q_CAPP  560UF 2.5V 20% OSCON  pkg THLF  page 271 : 1 = PVCCFA_EHV_FIVRA_CPU0 ; 2 = GND
PC621  Q_CAPP  560UF 2.5V 20% OSCON  pkg THLF  page 271 : 1 = PVCCFA_EHV_FIVRA_CPU0 ; 2 = GND
PC621_P1_1  Q_CAP  100NF 50V 10% X7R  pkg C0402  page 289 : 1 = PVCCFA_EHV_FIVRA_CPU1 ; 2 = GND
PC622  Q_CAPP  270UF 16V 20% OSCON  pkg THLF  page 271 : 1 = SW_P12V_PVCCFA_EHV_FIVRA_CPU0_L ; 2 = GND
PC623  Q_CAPP  330UF 2.5V +10/-35% SPCAP  pkg SMLF  page 271 : 1 = PVCCFA_EHV_FIVRA_CPU0 ; 2 = GND
PC624  Q_CAP  0.1UF 25V 10% X7R  pkg 0402  page 278 : 1 = PVCCD_HV_CPU0_ISENSE_P ; 2 = GND
PC627  Q_CAP  3300PF 50V 10% X7R  pkg 0402  page 278 : 1 = SH_PVCCD_HV_CPU0_R ; 2 = VSENSE_PVCCD_HV_CPU0_DN
PC628  Q_CAP  0.1UF 25V 10% X7R  pkg 0402  page 278 : 1 = PVCCD_HV_CPU0_ISENSE_N ; 2 = GND
PC629  Q_CAP  100NF 50V 10% EMPTY  pkg C0402  page 278 : 1 = PVCCD_HV_CPU0_VCC ; 2 = GND
PC630  Q_CAP  10UF 6.3V 20% X6S  pkg C0402  page 278 : 1 = PVCCD_HV_CPU0_VREF ; 2 = GND
PC631  Q_CAP  470PF 50V 10% X7R  pkg 0402  page 278 : 1 = PVCCD_HV_CPU0_ATSEN ; 2 = GND
PC632  Q_CAP  1UF 16V 10% X6S  pkg C0402  page 278 : 1 = PVCCD_HV_CPU0_VCC ; 2 = GND
PC633  Q_CAP  2.2UF 10V 10% X6S  pkg C0402  page 279 : 1 = PVCCD_HV_CPU0_VDD1 ; 2 = GND
PC634  Q_CAP  3300PF 50V 10% X7R  pkg 0402  page 279 : 1 = SW_P12V_PVCCINFAON_CPU0_FLT ; 2 = GND
PC635  Q_CAP  1UF 16V 10% X6S  pkg C0402  page 279 : 1 = SW_P12V_PVCCINFAON_CPU0_FLT ; 2 = GND
PC636  Q_CAP  100NF 50V 10% X7R  pkg C0402  page 279 : 1 = SW_PVCCD_HV_CPU0_BOOT1_R ; 2 = SW_PVCCD_HV_CPU0_BOOTR1
PC637  Q_CAP  22UF 16V 20% X6S  pkg C0805  page 279 : 1 = SW_P12V_PVCCINFAON_CPU0_FLT ; 2 = GND
PC638  Q_CAP  22UF 16V 20% X6S  pkg C0805  page 279 : 1 = SW_P12V_PVCCINFAON_CPU0_FLT ; 2 = GND
PC639  Q_CAP  100NF 50V 10% X7R  pkg C0402  page 279 : 1 = PVCCD_HV_CPU0 ; 2 = GND
PC641  Q_CAP  22UF 4V 20% X6S  pkg C0805  page 279 : 1 = PVCCD_HV_CPU0 ; 2 = GND
PC642  Q_CAP  22UF 4V 20% X6S  pkg C0805  page 279 : 1 = PVCCD_HV_CPU0 ; 2 = GND
PC644  Q_CAP  1UF 25V 10% X6S  pkg C0402  page 299 : 1 = PVPP_HBM_CPU1_VCC ; 2 = GND
PC720_P0_1  Q_CAP  22UF 16V 20% X6S  pkg C0805  page 271 : 1 = SW_P12V_PVCCFA_EHV_FIVRA_CPU0_R ; 2 = GND
PC721_P0_2  Q_CAP  22UF 16V 20% X6S  pkg C0805  page 271 : 1 = SW_P12V_PVCCFA_EHV_FIVRA_CPU0_L ; 2 = GND
PC722_P0_3  Q_CAP  22UF 16V 20% X6S  pkg C0805  page 272 : 1 = SW_P12V_PVCCFA_EHV_FIVRA_CPU0_R ; 2 = GND
PC723_P0_4  Q_CAP  22UF 16V 20% X6S  pkg C0805  page 272 : 1 = SW_P12V_PVCCFA_EHV_FIVRA_CPU0_L ; 2 = GND
PC724_P1_1  Q_CAP  22UF 16V 20% X6S  pkg C0805  page 289 : 1 = SW_P12V_PVCCFA_EHV_FIVRA_CPU1_R ; 2 = GND
PC725_P1_2  Q_CAP  22UF 16V 20% X6S  pkg C0805  page 289 : 1 = SW_P12V_PVCCFA_EHV_FIVRA_CPU1_L ; 2 = GND
PC726_P1_3  Q_CAP  22UF 16V 20% X6S  pkg C0805  page 290 : 1 = SW_P12V_PVCCFA_EHV_FIVRA_CPU1_R ; 2 = GND
PC727_P1_4  Q_CAP  22UF 16V 20% X6S  pkg C0805  page 290 : 1 = SW_P12V_PVCCFA_EHV_FIVRA_CPU1_L ; 2 = GND
PC813  Q_CAP  1UF 16V 10% X6S  pkg C0402  page 278 : 1 = PVCCD_HV_CPU0_ISENSE_N ; 2 = PVCCD_HV_CPU0_ISENSE_P
PC814  Q_CAP  1UF 16V 10% X6S  pkg C0402  page 296 : 1 = PVCCD_HV_CPU1_ISENSE_N ; 2 = PVCCD_HV_CPU1_ISENSE_P
PC831  Q_CAP  22UF 16V 20% X6S  pkg C0805  page 281 : 1 = SW_P12V_PVCCIN_CPU0_FLT ; 2 = GND
PC1171  Q_CAP  2.2UF 10V 10% X6S  pkg C0402  page 272 : 1 = PVCCFA_EHV_FIVRA_CPU0_VDD3 ; 2 = GND
PC1172  Q_CAP  2.2UF 10V 10% X6S  pkg C0402  page 272 : 1 = PVCCFA_EHV_FIVRA_CPU0_VDD4 ; 2 = GND
PC1173  Q_CAP  1UF 16V 10% X6S  pkg C0402  page 266 : 1 = PVCCIN_CPU0_VREF ; 2 = GND
PC1173_P0_3  Q_CAP  3300PF 50V 10% X7R  pkg 0402  page 272 : 1 = SW_P12V_PVCCFA_EHV_FIVRA_CPU0_R ; 2 = GND
PC1174_P0_4  Q_CAP  3300PF 50V 10% X7R  pkg 0402  page 272 : 1 = SW_P12V_PVCCFA_EHV_FIVRA_CPU0_L ; 2 = GND
PC1175_P0_3  Q_CAP  1UF 16V 10% X6S  pkg C0402  page 272 : 1 = SW_P12V_PVCCFA_EHV_FIVRA_CPU0_R ; 2 = GND
PC1176_P0_4  Q_CAP  1UF 16V 10% X6S  pkg C0402  page 272 : 1 = SW_P12V_PVCCFA_EHV_FIVRA_CPU0_L ; 2 = GND
PC1177  Q_CAP  100NF 50V 10% X7R  pkg C0402  page 272 : 1 = SW_PVCCFA_EHV_FIVRA_CPU0_BOOT3_ ; 2 = SW_PVCCFA_EHV_FIVRA_CPU0_BOOTR3
PC1178  Q_CAP  100NF 50V 10% X7R  pkg C0402  page 272 : 1 = SW_PVCCFA_EHV_FIVRA_CPU0_BOOT4_ ; 2 = SW_PVCCFA_EHV_FIVRA_CPU0_BOOTR4
PC1179_P0_3  Q_CAP  22UF 16V 20% X6S  pkg C0805  page 272 : 1 = SW_P12V_PVCCFA_EHV_FIVRA_CPU0_R ; 2 = GND
PC1180_P0_4  Q_CAP  22UF 16V 20% X6S  pkg C0805  page 272 : 1 = SW_P12V_PVCCFA_EHV_FIVRA_CPU0_L ; 2 = GND
PC1181_P0_3  Q_CAP  22UF 16V 20% X6S  pkg C0805  page 272 : 1 = SW_P12V_PVCCFA_EHV_FIVRA_CPU0_R ; 2 = GND
PC1182_P0_4  Q_CAP  22UF 16V 20% X6S  pkg C0805  page 272 : 1 = SW_P12V_PVCCFA_EHV_FIVRA_CPU0_L ; 2 = GND
PC1183  Q_CAPP  560UF 2.5V 20% OSCON  pkg THLF  page 272 : 1 = PVCCFA_EHV_FIVRA_CPU0 ; 2 = GND
PC1183_P0_3  Q_CAP  1UF 16V 10% X6S  pkg C0402  page 272 : 1 = PVCCFA_EHV_FIVRA_CPU0 ; 2 = GND
PC1183_P0_4  Q_CAP  100NF 50V 10% X7R  pkg C0402  page 272 : 1 = PVCCFA_EHV_FIVRA_CPU0 ; 2 = GND
PC1185  Q_CAPP  560UF 2.5V 20% OSCON  pkg THLF  page 272 : 1 = PVCCFA_EHV_FIVRA_CPU0 ; 2 = GND
PC1185_P0_3  Q_CAP  22UF 4V 20% X6S  pkg C0805  page 272 : 1 = PVCCFA_EHV_FIVRA_CPU0 ; 2 = GND
PC1186  Q_CAPP  560UF 2.5V 20% OSCON  pkg THLF  page 272 : 1 = PVCCFA_EHV_FIVRA_CPU0 ; 2 = GND
PC1186_P0_4  Q_CAP  22UF 4V 20% X6S  pkg C0805  page 272 : 1 = PVCCFA_EHV_FIVRA_CPU0 ; 2 = GND
PC1187  Q_CAPP  330UF 2.5V +10/-35% SPCAP  pkg SMLF  page 272 : 1 = PVCCFA_EHV_FIVRA_CPU0 ; 2 = GND
PC1187_P0_3  Q_CAP  22UF 4V 20% X6S  pkg C0805  page 272 : 1 = PVCCFA_EHV_FIVRA_CPU0 ; 2 = GND
PC1188_P0_4  Q_CAP  22UF 4V 20% X6S  pkg C0805  page 272 : 1 = PVCCFA_EHV_FIVRA_CPU0 ; 2 = GND
PC1189  Q_CAPP  270UF 16V 20% OSCON  pkg THLF  page 272 : 1 = SW_P12V_PVCCFA_EHV_FIVRA_CPU0_R ; 2 = GND
PC1191  Q_CAP  2.2UF 10V 10% X6S  pkg C0402  page 290 : 1 = PVCCFA_EHV_FIVRA_CPU1_VDD3 ; 2 = GND
PC1192  Q_CAP  2.2UF 10V 10% X6S  pkg C0402  page 290 : 1 = PVCCFA_EHV_FIVRA_CPU1_VDD4 ; 2 = GND
PC1193  Q_CAP  1UF 16V 10% X6S  pkg C0402  page 292 : 1 = PVCCINFAON_CPU1_VREF ; 2 = GND
PC1193_P1_3  Q_CAP  3300PF 50V 10% X7R  pkg 0402  page 290 : 1 = SW_P12V_PVCCFA_EHV_FIVRA_CPU1_R ; 2 = GND
PC1194  Q_CAP  1UF 16V 10% X6S  pkg C0402  page 284 : 1 = PVCCIN_CPU1_VREF ; 2 = GND
PC1194_P1_4  Q_CAP  3300PF 50V 10% X7R  pkg 0402  page 290 : 1 = SW_P12V_PVCCFA_EHV_FIVRA_CPU1_L ; 2 = GND
PC1195_P1_3  Q_CAP  1UF 16V 10% X6S  pkg C0402  page 290 : 1 = SW_P12V_PVCCFA_EHV_FIVRA_CPU1_R ; 2 = GND
PC1196  Q_CAP  1UF 16V 10% X6S  pkg C0402  page 278 : 1 = PVCCD_HV_CPU0_VREF ; 2 = GND
PC1196_P1_4  Q_CAP  1UF 16V 10% X6S  pkg C0402  page 290 : 1 = SW_P12V_PVCCFA_EHV_FIVRA_CPU1_L ; 2 = GND
PC1197  Q_CAP  100NF 50V 10% X7R  pkg C0402  page 290 : 1 = SW_PVCCFA_EHV_FIVRA_CPU1_BOOT3_ ; 2 = SW_PVCCFA_EHV_FIVRA_CPU1_BOOTR3
PC1198  Q_CAP  100NF 50V 10% X7R  pkg C0402  page 290 : 1 = SW_PVCCFA_EHV_FIVRA_CPU1_BOOT4_ ; 2 = SW_PVCCFA_EHV_FIVRA_CPU1_BOOTR4
PC1199_P1_3  Q_CAP  22UF 16V 20% X6S  pkg C0805  page 290 : 1 = SW_P12V_PVCCFA_EHV_FIVRA_CPU1_R ; 2 = GND
PC1200_P1_4  Q_CAP  22UF 16V 20% X6S  pkg C0805  page 290 : 1 = SW_P12V_PVCCFA_EHV_FIVRA_CPU1_L ; 2 = GND
PC1201  Q_CAPP  560UF 2.5V 20% OSCON  pkg THLF  page 290 : 1 = PVCCFA_EHV_FIVRA_CPU1 ; 2 = GND
PC1201_P1_3  Q_CAP  22UF 16V 20% X6S  pkg C0805  page 290 : 1 = SW_P12V_PVCCFA_EHV_FIVRA_CPU1_R ; 2 = GND
PC1202_P1_4  Q_CAP  22UF 16V 20% X6S  pkg C0805  page 290 : 1 = SW_P12V_PVCCFA_EHV_FIVRA_CPU1_L ; 2 = GND
PC1203  Q_CAPP  560UF 2.5V 20% OSCON  pkg THLF  page 290 : 1 = PVCCFA_EHV_FIVRA_CPU1 ; 2 = GND
PC1203_P1_4  Q_CAP  100NF 50V 10% X7R  pkg C0402  page 290 : 1 = PVCCFA_EHV_FIVRA_CPU1 ; 2 = GND
PC1204  Q_CAPP  560UF 2.5V 20% OSCON  pkg THLF  page 290 : 1 = PVCCFA_EHV_FIVRA_CPU1 ; 2 = GND
PC1204_P1_3  Q_CAP  1UF 16V 10% X6S  pkg C0402  page 290 : 1 = PVCCFA_EHV_FIVRA_CPU1 ; 2 = GND
PC1205  Q_CAPP  330UF 2.5V +10/-35% SPCAP  pkg SMLF  page 290 : 1 = PVCCFA_EHV_FIVRA_CPU1 ; 2 = GND
PC1206  Q_CAP  22UF 4V 20% X6S  pkg C0805  page 282 : 1 = PVNN_MAIN_CPU0 ; 2 = GND
PC1206_P1_3  Q_CAP  22UF 4V 20% X6S  pkg C0805  page 290 : 1 = PVCCFA_EHV_FIVRA_CPU1 ; 2 = GND
PC1207  Q_CAP  22UF 4V 20% X6S  pkg C0805  page 300 : 1 = PVNN_MAIN_CPU1 ; 2 = GND
PC1207_P1_4  Q_CAP  22UF 4V 20% X6S  pkg C0805  page 290 : 1 = PVCCFA_EHV_FIVRA_CPU1 ; 2 = GND
PC1208_P1_3  Q_CAP  22UF 4V 20% X6S  pkg C0805  page 290 : 1 = PVCCFA_EHV_FIVRA_CPU1 ; 2 = GND
PC1209_P1_4  Q_CAP  22UF 4V 20% X6S  pkg C0805  page 290 : 1 = PVCCFA_EHV_FIVRA_CPU1 ; 2 = GND
PC1210  Q_CAPP  270UF 16V 20% OSCON  pkg THLF  page 290 : 1 = SW_P12V_PVCCFA_EHV_FIVRA_CPU1_R ; 2 = GND
PC1211_P0_1  Q_CAP  2.2UF 10V 10% X6S  pkg C0402  page 271 : 1 = PVCCFA_EHV_FIVRA_CPU0_PVCC1 ; 2 = GND
PC1212_P0_2  Q_CAP  2.2UF 10V 10% X6S  pkg C0402  page 271 : 1 = PVCCFA_EHV_FIVRA_CPU0_PVCC2 ; 2 = GND
PC1213_P0_3  Q_CAP  2.2UF 10V 10% X6S  pkg C0402  page 272 : 1 = PVCCFA_EHV_FIVRA_CPU0_PVCC1 ; 2 = GND
PC1214_P0_4  Q_CAP  2.2UF 10V 10% X6S  pkg C0402  page 272 : 1 = PVCCFA_EHV_FIVRA_CPU0_PVCC2 ; 2 = GND
PC1215  Q_CAPP  100UF 16V 20% OSCON  pkg SMLF  page 262 : 1 = SW_P12V_AUX_P1V05_PCH_AUX_FLT ; 2 = GND
PC1216  Q_CAP  22UF 16V 20% X6S  pkg C0805  page 262 : 1 = SW_P12V_AUX_P1V05_PCH_AUX_FLT ; 2 = GND
PC1217  Q_CAP  22UF 16V 20% X6S  pkg C0805  page 262 : 1 = SW_P12V_AUX_P1V05_PCH_AUX_FLT ; 2 = GND
PC1218  Q_CAP  22UF 16V 20% X6S  pkg C0805  page 262 : 1 = SW_P12V_AUX_P1V05_PCH_AUX_FLT ; 2 = GND
PC1219  Q_CAP  1UF 16V 10% X6S  pkg C0402  page 262 : 1 = SW_P12V_AUX_P1V05_PCH_AUX_FLT ; 2 = GND
PC1221  Q_CAP  0.1UF 25V 10% X7R  pkg 0402  page 262 : 1 = P1V05_PCH_AUX_REF ; 2 = SH_P1V05_PCH_AUX_N
PC1222  Q_CAP  0.22UF 25V 10% X7R  pkg C0402  page 262 : 1 = SW_P1V05_PCH_AUX_BST ; 2 = SW_P1V05_PCH_AUX_SW
PC1223  Q_CAP  680PF 50V 10% X7R  pkg 0402  page 262 : 1 = P1V05_PCH_AUX_FB ; 2 = SH_P1V05_PCH_AUX_P
PC1224  Q_CAP  0.1UF 25V 10% X7R  pkg 0402  page 262 : 1 = P1V05_PCH_AUX ; 2 = GND
PC1225  Q_CAP  47UF 4V 20% X6S  pkg C0805  page 262 : 1 = P1V05_PCH_AUX ; 2 = GND
PC1226  Q_CAP  47UF 4V 20% X6S  pkg C0805  page 262 : 1 = P1V05_PCH_AUX ; 2 = GND
PC1227  Q_CAPP  560UF 2.5V 20% OSCON  pkg THLF  page 262 : 1 = P1V05_PCH_AUX ; 2 = GND
PC1229  Q_CAPP  330UF 2V 35% SPCAP  pkg SMLF  page 262 : 1 = P1V05_PCH_AUX ; 2 = GND
PC1230  Q_CAPP  560UF 2.5V 20% OSCON  pkg THLF  page 262 : 1 = P1V05_PCH_AUX ; 2 = GND
PC1232  Q_CAP  10UF 16V 10% X6S  pkg C0805  page 263 : 1 = SW_P1V8_PCH_AUX_FLT ; 2 = GND
PC1233  Q_CAP  10UF 16V 10% X6S  pkg C0805  page 263 : 1 = SW_P1V8_PCH_AUX_FLT ; 2 = GND
PC1234  Q_CAP  100NF 50V 10% X7R  pkg C0402  page 263 : 1 = SW_P1V8_PCH_AUX_FLT ; 2 = GND
PC1235  Q_CAP  0.22UF 25V 10% X7R  pkg C0402  page 263 : 1 = SW_P1V8_PCH_AUX_BST ; 2 = SW_P1V8_PCH_AUX_SW
PC1236  Q_CAP  100NF 50V 10% X7R  pkg C0402  page 263 : 1 = P1V8_PCH_AUX ; 2 = GND
PC1237  Q_CAP  22UF 4V 20% X6S  pkg C0805  page 263 : 1 = P1V8_PCH_AUX ; 2 = GND
PC1238  Q_CAP  22UF 4V 20% X6S  pkg C0805  page 263 : 1 = P1V8_PCH_AUX ; 2 = GND
PC1239  Q_CAP  22UF 4V 20% X6S  pkg C0805  page 263 : 1 = P1V8_PCH_AUX ; 2 = GND
PC1240  Q_CAP  22UF 4V 20% X6S  pkg C0805  page 263 : 1 = P1V8_PCH_AUX ; 2 = GND
PC1241  Q_CAP  22UF 4V 20% X6S  pkg C0805  page 263 : 1 = P1V8_PCH_AUX ; 2 = GND
PC1242_P1_1  Q_CAP  2.2UF 10V 10% X6S  pkg C0402  page 289 : 1 = PVCCFA_EHV_FIVRA_CPU1_PVCC1 ; 2 = GND
PC1243_P1_2  Q_CAP  2.2UF 10V 10% X6S  pkg C0402  page 289 : 1 = PVCCFA_EHV_FIVRA_CPU1_PVCC2 ; 2 = GND
PC1244_P1_3  Q_CAP  2.2UF 10V 10% X6S  pkg C0402  page 290 : 1 = PVCCFA_EHV_FIVRA_CPU1_PVCC1 ; 2 = GND
PC1245_P1_4  Q_CAP  2.2UF 10V 10% X6S  pkg C0402  page 290 : 1 = PVCCFA_EHV_FIVRA_CPU1_PVCC2 ; 2 = GND
PC1247  Q_CAP  22UF 16V 20% X6S  pkg C0805  page 281 : 1 = SW_P12V_PVCCIN_CPU0_FLT ; 2 = GND
PC1248  Q_CAP  22UF 16V 20% X6S  pkg C0805  page 281 : 1 = SW_P12V_PVCCIN_CPU0_FLT ; 2 = GND
PC1249  Q_CAP  1UF 16V 10% X6S  pkg C0402  page 281 : 1 = SW_P12V_PVCCIN_CPU0_FLT ; 2 = GND
PC1251  Q_CAP  0.1UF 25V 10% X7R  pkg 0402  page 281 : 1 = PVPP_HBM_CPU0_REF ; 2 = SH_PVPP_HBM_CPU0_N
PC1252  Q_CAP  0.22UF 25V 10% X7R  pkg C0402  page 281 : 1 = SW_PVPP_HBM_CPU0_BST ; 2 = SW_PVPP_HBM_CPU0_SW
PC1253  Q_CAP  680PF 50V 10% X7R  pkg C0402  page 281 : 1 = PVPP_HBM_CPU0_FB ; 2 = SH_PVPP_HBM_CPU0_P
